FILE_TYPE = CONNECTIVITY;
{Allegro Design Entry HDL 17.2-2016 S081 (4005846) 1/11/2022}
"PAGE_NUMBER" = 77;
0"NC";
1"PVCCFA_EHV_FIVRA_CPU1\g";
2"PVCCD_HV_CPU1\g";
3"PVCCIN_CPU1\g";
4"PVCCIN_CPU1\g";
5"PVCCIN_CPU1\g";
6"PVCCIN_CPU1\g";
7"PVCCIN_CPU1\g";
8"PVCCINFAON_CPU1\g";
9"PVCCFA_EHV_CPU1\g";
10"PVNN_MAIN_CPU1\g";
11"PVCCIN_CPU1\g";
12"PVCCIN_CPU1\g";
13"PVCCIN_CPU1\g";
14"PVCCIN_CPU1\g";
15"GND\g";
16"GND\g";
17"GND\g";
18"GND\g";
19"GND\g";
20"GND\g";
21"GND\g";
22"GND\g";
23"GND\g"VOLTAGE"0";
24"GND\g";
25"GND\g";
26"GND\g";
27"GND\g";
28"GND\g";
%"Q_CAP"
"1","(-7250,2225)","0","pure_quanta","I1";
;
PART_NUMBER"CH622KMEB01"
VOLTAGE"4V"
TOLERANCE"20%"
VALUE"22UF"
MATERIAL"X6S"
PACK_TYPE"C0402"
$LOCATION"C424"
CDS_LIB"pure_quanta"
CDS_LOCATION"C424"
$SEC"1"
CDS_SEC"1";
"B"
$PN"2"17;
"A"
$PN"1"1;
%"Q_CAP"
"1","(-7250,3850)","0","pure_quanta","I10";
;
PART_NUMBER"CH647KMEA04"
VOLTAGE"4V"
TOLERANCE"20%"
PACK_TYPE"C0805"
VALUE"47UF"
MATERIAL"X6S"
$LOCATION"C225"
CDS_LIB"pure_quanta"
$LOCATION"C225"
CDS_LOCATION"C225"
$SEC"1"
CDS_SEC"1";
"B"
$PN"2"18;
"A"
$PN"1"3;
%"Q_CAP"
"1","(-2750,6925)","0","pure_quanta","I100";
;
PART_NUMBER"CH622KMEB01"
VOLTAGE"4V"
TOLERANCE"20%"
PACK_TYPE"C0402"
MATERIAL"X6S"
VALUE"22UF"
$LOCATION"C271"
CDS_LIB"pure_quanta"
$LOCATION"C271"
CDS_LOCATION"C271"
$SEC"1"
CDS_SEC"1";
"B"
$PN"2"28;
"A"
$PN"1"14;
%"Q_CAP"
"1","(-2275,5400)","0","pure_quanta","I101";
;
PART_NUMBER"CH622KMEB01"
VOLTAGE"4V"
TOLERANCE"20%"
MATERIAL"X6S"
PACK_TYPE"C0402"
VALUE"22UF"
$LOCATION"C277"
CDS_LIB"pure_quanta"
$LOCATION"C277"
CDS_LOCATION"C277"
$SEC"1"
CDS_SEC"1";
"B"
$PN"2"26;
"A"
$PN"1"12;
%"Q_CAP"
"1","(-1825,5400)","0","pure_quanta","I102";
;
PART_NUMBER"CH622KMEB01"
VOLTAGE"4V"
MATERIAL"X6S"
TOLERANCE"20%"
VALUE"22UF"
PACK_TYPE"C0402"
$LOCATION"C281"
CDS_LIB"pure_quanta"
$LOCATION"C281"
CDS_LOCATION"C281"
$SEC"1"
CDS_SEC"1";
"B"
$PN"2"26;
"A"
$PN"1"12;
%"Q_CAP"
"1","(-2300,6150)","0","pure_quanta","I103";
;
PART_NUMBER"CH622KMEB01"
TOLERANCE"20%"
VOLTAGE"4V"
VALUE"22UF"
PACK_TYPE"C0402"
MATERIAL"X6S"
$LOCATION"C276"
CDS_LIB"pure_quanta"
$LOCATION"C276"
CDS_LOCATION"C276"
$SEC"1"
CDS_SEC"1";
"B"
$PN"2"27;
"A"
$PN"1"13;
%"Q_CAP"
"1","(-2300,6925)","0","pure_quanta","I104";
;
PART_NUMBER"CH622KMEB01"
VOLTAGE"4V"
TOLERANCE"20%"
PACK_TYPE"C0402"
MATERIAL"X6S"
VALUE"22UF"
$LOCATION"C275"
CDS_LIB"pure_quanta"
$LOCATION"C275"
CDS_LOCATION"C275"
$SEC"1"
CDS_SEC"1";
"B"
$PN"2"28;
"A"
$PN"1"14;
%"Q_CAP"
"1","(-1850,6150)","0","pure_quanta","I105";
;
PART_NUMBER"CH622KMEB01"
VOLTAGE"4V"
VALUE"22UF"
TOLERANCE"20%"
MATERIAL"X6S"
PACK_TYPE"C0402"
$LOCATION"C280"
CDS_LIB"pure_quanta"
$LOCATION"C280"
CDS_LOCATION"C280"
$SEC"1"
CDS_SEC"1";
"B"
$PN"2"27;
"A"
$PN"1"13;
%"Q_CAP"
"1","(-1850,6925)","0","pure_quanta","I106";
;
PART_NUMBER"CH622KMEB01"
VOLTAGE"4V"
TOLERANCE"20%"
MATERIAL"X6S"
VALUE"22UF"
PACK_TYPE"C0402"
$LOCATION"C279"
CDS_LIB"pure_quanta"
$LOCATION"C279"
CDS_LOCATION"C279"
$SEC"1"
CDS_SEC"1";
"B"
$PN"2"28;
"A"
$PN"1"14;
%"UNIVERSAL_POWER"
"1","(-2750,7200)","0","logical_power","I107";
;
HDL_POWER"PVCCIN_CPU1"
CDS_LIB"logical_power";
"A"14;
%"UNIVERSAL_GND"
"1","(-625,2725)","0","logical_power","I108";
;
CDS_LIB"logical_power"
HDL_POWER"GND";
"A"24;
%"Q_CAP"
"1","(-1525,3050)","0","pure_quanta","I109";
;
PART_NUMBER"CH622KMEB01"
VALUE"22UF"
VOLTAGE"4V"
TOLERANCE"20%"
PACK_TYPE"C0402"
MATERIAL"X6S"
$LOCATION"C444"
CDS_LIB"pure_quanta"
CDS_LOCATION"C444"
$SEC"1"
CDS_SEC"1";
"B"
$PN"2"24;
"A"
$PN"1"9;
%"Q_CAP"
"1","(-6800,3850)","0","pure_quanta","I11";
;
PART_NUMBER"CH647KMEA04"
TOLERANCE"20%"
VOLTAGE"4V"
PACK_TYPE"C0805"
VALUE"47UF"
MATERIAL"X6S"
$LOCATION"C230"
CDS_LIB"pure_quanta"
$LOCATION"C230"
CDS_LOCATION"C230"
$SEC"1"
CDS_SEC"1";
"B"
$PN"2"18;
"A"
$PN"1"3;
%"Q_CAP"
"1","(-1075,3050)","0","pure_quanta","I110";
;
PART_NUMBER"CH622KMEB01"
TOLERANCE"20%"
VALUE"22UF"
VOLTAGE"4V"
MATERIAL"X6S"
PACK_TYPE"C0402"
$LOCATION"C445"
CDS_LIB"pure_quanta"
CDS_LOCATION"C445"
$SEC"1"
CDS_SEC"1";
"B"
$PN"2"24;
"A"
$PN"1"9;
%"Q_CAP"
"1","(-1375,4625)","0","pure_quanta","I111";
;
PART_NUMBER"CH622KMEB01"
VOLTAGE"4V"
TOLERANCE"20%"
PACK_TYPE"C0402"
MATERIAL"X6S"
VALUE"22UF"
$LOCATION"C286"
CDS_LIB"pure_quanta"
$LOCATION"C286"
CDS_LOCATION"C286"
$SEC"1"
CDS_SEC"1";
"B"
$PN"2"25;
"A"
$PN"1"11;
%"Q_CAP"
"1","(-925,4625)","0","pure_quanta","I112";
;
PART_NUMBER"CH622KMEB01"
TOLERANCE"20%"
VOLTAGE"4V"
MATERIAL"X6S"
VALUE"22UF"
PACK_TYPE"C0402"
$LOCATION"C290"
CDS_LIB"pure_quanta"
$LOCATION"C290"
CDS_LOCATION"C290"
$SEC"1"
CDS_SEC"1";
"B"
$PN"2"25;
"A"
$PN"1"11;
%"Q_CAP"
"1","(-625,3050)","0","pure_quanta","I113";
;
PART_NUMBER"CH622KMEB01"
VALUE"22UF"
VOLTAGE"4V"
TOLERANCE"20%"
MATERIAL"X6S"
PACK_TYPE"C0402"
$LOCATION"C446"
CDS_LIB"pure_quanta"
CDS_LOCATION"C446"
$SEC"1"
CDS_SEC"1";
"B"
$PN"2"24;
"A"
$PN"1"9;
%"Q_CAP"
"1","(-475,4625)","0","pure_quanta","I114";
;
PART_NUMBER"CH622KMEB01"
VOLTAGE"4V"
TOLERANCE"20%"
VALUE"22UF"
PACK_TYPE"C0402"
MATERIAL"X6S"
$LOCATION"C294"
CDS_LIB"pure_quanta"
$LOCATION"C294"
CDS_LOCATION"C294"
$SEC"1"
CDS_SEC"1";
"B"
$PN"2"25;
"A"
$PN"1"11;
%"Q_CAP"
"1","(-25,4625)","0","pure_quanta","I115";
;
PART_NUMBER"CH622KMEB01"
TOLERANCE"20%"
VOLTAGE"4V"
MATERIAL"X6S"
VALUE"22UF"
PACK_TYPE"C0402"
$LOCATION"C298"
CDS_LIB"pure_quanta"
$LOCATION"C298"
CDS_LOCATION"C298"
$SEC"1"
CDS_SEC"1";
"B"
$PN"2"25;
"A"
$PN"1"11;
%"UNIVERSAL_GND"
"1","(875,4275)","0","logical_power","I116";
;
CDS_LIB"logical_power"
HDL_POWER"GND";
"A"25;
%"Q_CAP"
"1","(425,4625)","0","pure_quanta","I117";
;
PART_NUMBER"CH622KMEB01"
TOLERANCE"20%"
VOLTAGE"4V"
MATERIAL"X6S"
VALUE"22UF"
PACK_TYPE"C0402"
$LOCATION"C302"
CDS_LIB"pure_quanta"
$LOCATION"C302"
CDS_LOCATION"C302"
$SEC"1"
CDS_SEC"1";
"B"
$PN"2"25;
"A"
$PN"1"11;
%"Q_CAP"
"1","(875,4625)","0","pure_quanta","I118";
;
PART_NUMBER"CH622KMEB01"
TOLERANCE"20%"
VOLTAGE"4V"
MATERIAL"X6S"
VALUE"22UF"
PACK_TYPE"C0402"
$LOCATION"C306"
CDS_LIB"pure_quanta"
$LOCATION"C306"
CDS_LOCATION"C306"
$SEC"1"
CDS_SEC"1";
"B"
$PN"2"25;
"A"
$PN"1"11;
%"Q_CAP"
"1","(-1375,5400)","0","pure_quanta","I119";
;
PART_NUMBER"CH622KMEB01"
VOLTAGE"4V"
PACK_TYPE"C0402"
MATERIAL"X6S"
VALUE"22UF"
TOLERANCE"20%"
$LOCATION"C285"
CDS_LIB"pure_quanta"
$LOCATION"C285"
CDS_LOCATION"C285"
$SEC"1"
CDS_SEC"1";
"B"
$PN"2"26;
"A"
$PN"1"12;
%"UNIVERSAL_POWER"
"1","(-7250,4125)","0","logical_power","I12";
;
HDL_POWER"PVCCIN_CPU1"
CDS_LIB"logical_power";
"A"3;
%"Q_CAP"
"1","(-925,5400)","0","pure_quanta","I120";
;
PART_NUMBER"CH622KMEB01"
VOLTAGE"4V"
PACK_TYPE"C0402"
MATERIAL"X6S"
VALUE"22UF"
TOLERANCE"20%"
$LOCATION"C289"
CDS_LIB"pure_quanta"
$LOCATION"C289"
CDS_LOCATION"C289"
$SEC"1"
CDS_SEC"1";
"B"
$PN"2"26;
"A"
$PN"1"12;
%"Q_CAP"
"1","(-1400,6150)","0","pure_quanta","I121";
;
PART_NUMBER"CH622KMEB01"
TOLERANCE"20%"
VALUE"22UF"
VOLTAGE"4V"
MATERIAL"X6S"
PACK_TYPE"C0402"
$LOCATION"C284"
CDS_LIB"pure_quanta"
$LOCATION"C284"
CDS_LOCATION"C284"
$SEC"1"
CDS_SEC"1";
"B"
$PN"2"27;
"A"
$PN"1"13;
%"Q_CAP"
"1","(-1400,6925)","0","pure_quanta","I122";
;
PART_NUMBER"CH622KMEB01"
VOLTAGE"4V"
TOLERANCE"20%"
PACK_TYPE"C0402"
MATERIAL"X6S"
VALUE"22UF"
$LOCATION"C283"
CDS_LIB"pure_quanta"
$LOCATION"C283"
CDS_LOCATION"C283"
$SEC"1"
CDS_SEC"1";
"B"
$PN"2"28;
"A"
$PN"1"14;
%"Q_CAP"
"1","(-950,6150)","0","pure_quanta","I123";
;
PART_NUMBER"CH622KMEB01"
TOLERANCE"20%"
VOLTAGE"4V"
VALUE"22UF"
MATERIAL"X6S"
PACK_TYPE"C0402"
$LOCATION"C288"
CDS_LIB"pure_quanta"
$LOCATION"C288"
CDS_LOCATION"C288"
$SEC"1"
CDS_SEC"1";
"B"
$PN"2"27;
"A"
$PN"1"13;
%"Q_CAP"
"1","(-950,6925)","0","pure_quanta","I124";
;
PART_NUMBER"CH622KMEB01"
TOLERANCE"20%"
VOLTAGE"4V"
PACK_TYPE"C0402"
MATERIAL"X6S"
VALUE"22UF"
$LOCATION"C287"
CDS_LIB"pure_quanta"
$LOCATION"C287"
CDS_LOCATION"C287"
$SEC"1"
CDS_SEC"1";
"B"
$PN"2"28;
"A"
$PN"1"14;
%"Q_CAP"
"1","(-475,5400)","0","pure_quanta","I125";
;
PART_NUMBER"CH622KMEB01"
VOLTAGE"4V"
PACK_TYPE"C0402"
MATERIAL"X6S"
TOLERANCE"20%"
VALUE"22UF"
$LOCATION"C293"
CDS_LIB"pure_quanta"
$LOCATION"C293"
CDS_LOCATION"C293"
$SEC"1"
CDS_SEC"1";
"B"
$PN"2"26;
"A"
$PN"1"12;
%"Q_CAP"
"1","(-25,5400)","0","pure_quanta","I126";
;
PART_NUMBER"CH622KMEB01"
VOLTAGE"4V"
PACK_TYPE"C0402"
MATERIAL"X6S"
TOLERANCE"20%"
VALUE"22UF"
$LOCATION"C297"
CDS_LIB"pure_quanta"
$LOCATION"C297"
CDS_LOCATION"C297"
$SEC"1"
CDS_SEC"1";
"B"
$PN"2"26;
"A"
$PN"1"12;
%"Q_CAP"
"1","(-500,6150)","0","pure_quanta","I127";
;
PART_NUMBER"CH622KMEB01"
VOLTAGE"4V"
VALUE"22UF"
TOLERANCE"20%"
PACK_TYPE"C0402"
MATERIAL"X6S"
$LOCATION"C292"
CDS_LIB"pure_quanta"
$LOCATION"C292"
CDS_LOCATION"C292"
$SEC"1"
CDS_SEC"1";
"B"
$PN"2"27;
"A"
$PN"1"13;
%"Q_CAP"
"1","(-500,6925)","0","pure_quanta","I128";
;
PART_NUMBER"CH622KMEB01"
TOLERANCE"20%"
VOLTAGE"4V"
PACK_TYPE"C0402"
VALUE"22UF"
MATERIAL"X6S"
$LOCATION"C291"
CDS_LIB"pure_quanta"
$LOCATION"C291"
CDS_LOCATION"C291"
$SEC"1"
CDS_SEC"1";
"B"
$PN"2"28;
"A"
$PN"1"14;
%"Q_CAP"
"1","(-50,6150)","0","pure_quanta","I129";
;
PART_NUMBER"CH622KMEB01"
VOLTAGE"4V"
VALUE"22UF"
TOLERANCE"20%"
MATERIAL"X6S"
PACK_TYPE"C0402"
$LOCATION"C296"
CDS_LIB"pure_quanta"
$LOCATION"C296"
CDS_LOCATION"C296"
$SEC"1"
CDS_SEC"1";
"B"
$PN"2"27;
"A"
$PN"1"13;
%"Q_CAP"
"1","(-7250,4625)","0","pure_quanta","I13";
;
PART_NUMBER"CH6101MEB03"
VOLTAGE"6.3V"
VALUE"10UF"
PACK_TYPE"C0402"
MATERIAL"X6S"
TOLERANCE"20%"
$LOCATION"C224"
CDS_LIB"pure_quanta"
$LOCATION"C224"
CDS_LOCATION"C224"
$SEC"1"
CDS_SEC"1";
"B"
$PN"2"19;
"A"
$PN"1"4;
%"Q_CAP"
"1","(-50,6925)","0","pure_quanta","I130";
;
PART_NUMBER"CH622KMEB01"
VOLTAGE"4V"
TOLERANCE"20%"
PACK_TYPE"C0402"
MATERIAL"X6S"
VALUE"22UF"
$LOCATION"C295"
CDS_LIB"pure_quanta"
$LOCATION"C295"
CDS_LOCATION"C295"
$SEC"1"
CDS_SEC"1";
"B"
$PN"2"28;
"A"
$PN"1"14;
%"Q_CAP"
"1","(400,6925)","0","pure_quanta","I131";
;
PART_NUMBER"CH622KMEB01"
VOLTAGE"4V"
TOLERANCE"20%"
PACK_TYPE"C0402"
MATERIAL"X6S"
VALUE"22UF"
$LOCATION"C299"
CDS_LIB"pure_quanta"
$LOCATION"C299"
CDS_LOCATION"C299"
$SEC"1"
CDS_SEC"1";
"B"
$PN"2"28;
"A"
$PN"1"14;
%"Q_CAP"
"1","(400,6150)","0","pure_quanta","I132";
;
PART_NUMBER"CH622KMEB01"
VOLTAGE"4V"
VALUE"22UF"
TOLERANCE"20%"
PACK_TYPE"C0402"
MATERIAL"X6S"
$LOCATION"C300"
CDS_LIB"pure_quanta"
$LOCATION"C300"
CDS_LOCATION"C300"
$SEC"1"
CDS_SEC"1";
"B"
$PN"2"27;
"A"
$PN"1"13;
%"Q_CAP"
"1","(425,5400)","0","pure_quanta","I133";
;
PART_NUMBER"CH622KMEB01"
VOLTAGE"4V"
PACK_TYPE"C0402"
MATERIAL"X6S"
TOLERANCE"20%"
VALUE"22UF"
$LOCATION"C301"
CDS_LIB"pure_quanta"
$LOCATION"C301"
CDS_LOCATION"C301"
$SEC"1"
CDS_SEC"1";
"B"
$PN"2"26;
"A"
$PN"1"12;
%"Q_CAP"
"1","(875,5400)","0","pure_quanta","I134";
;
PART_NUMBER"CH622KMEB01"
VOLTAGE"4V"
PACK_TYPE"C0402"
MATERIAL"X6S"
TOLERANCE"20%"
VALUE"22UF"
$LOCATION"C305"
CDS_LIB"pure_quanta"
$LOCATION"C305"
CDS_LOCATION"C305"
$SEC"1"
CDS_SEC"1";
"B"
$PN"2"26;
"A"
$PN"1"12;
%"UNIVERSAL_GND"
"1","(1325,5050)","0","logical_power","I135";
;
CDS_LIB"logical_power"
HDL_POWER"GND";
"A"26;
%"Q_CAP"
"1","(1325,5400)","0","pure_quanta","I136";
;
PART_NUMBER"CH622KMEB01"
VOLTAGE"4V"
TOLERANCE"20%"
MATERIAL"X6S"
PACK_TYPE"C0402"
VALUE"22UF"
$LOCATION"C309"
CDS_LIB"pure_quanta"
$LOCATION"C309"
CDS_LOCATION"C309"
$SEC"1"
CDS_SEC"1";
"B"
$PN"2"26;
"A"
$PN"1"12;
%"UNIVERSAL_GND"
"1","(1300,5800)","0","logical_power","I137";
;
CDS_LIB"logical_power"
HDL_POWER"GND";
"A"27;
%"Q_CAP"
"1","(850,6150)","0","pure_quanta","I138";
;
PART_NUMBER"CH622KMEB01"
VALUE"22UF"
VOLTAGE"4V"
TOLERANCE"20%"
PACK_TYPE"C0402"
MATERIAL"X6S"
$LOCATION"C304"
CDS_LIB"pure_quanta"
$LOCATION"C304"
CDS_LOCATION"C304"
$SEC"1"
CDS_SEC"1";
"B"
$PN"2"27;
"A"
$PN"1"13;
%"Q_CAP"
"1","(850,6925)","0","pure_quanta","I139";
;
PART_NUMBER"CH622KMEB01"
VOLTAGE"4V"
TOLERANCE"20%"
PACK_TYPE"C0402"
MATERIAL"X6S"
VALUE"22UF"
$LOCATION"C303"
CDS_LIB"pure_quanta"
$LOCATION"C303"
CDS_LOCATION"C303"
$SEC"1"
CDS_SEC"1";
"B"
$PN"2"28;
"A"
$PN"1"14;
%"Q_CAP"
"1","(-6800,4625)","0","pure_quanta","I14";
;
PART_NUMBER"CH6101MEB03"
VOLTAGE"6.3V"
VALUE"10UF"
TOLERANCE"20%"
MATERIAL"X6S"
PACK_TYPE"C0402"
$LOCATION"C229"
CDS_LIB"pure_quanta"
$LOCATION"C229"
CDS_LOCATION"C229"
$SEC"1"
CDS_SEC"1";
"B"
$PN"2"19;
"A"
$PN"1"4;
%"Q_CAP"
"1","(1300,6150)","0","pure_quanta","I140";
;
PART_NUMBER"CH622KMEB01"
TOLERANCE"20%"
VOLTAGE"4V"
VALUE"22UF"
PACK_TYPE"C0402"
MATERIAL"X6S"
$LOCATION"C308"
CDS_LIB"pure_quanta"
$LOCATION"C308"
CDS_LOCATION"C308"
$SEC"1"
CDS_SEC"1";
"B"
$PN"2"27;
"A"
$PN"1"13;
%"UNIVERSAL_GND"
"1","(1300,6575)","0","logical_power","I141";
;
CDS_LIB"logical_power"
HDL_POWER"GND";
"A"28;
%"Q_CAP"
"1","(1300,6925)","0","pure_quanta","I142";
;
PART_NUMBER"CH622KMEB01"
VOLTAGE"4V"
TOLERANCE"20%"
PACK_TYPE"C0402"
MATERIAL"X6S"
VALUE"22UF"
$LOCATION"C307"
CDS_LIB"pure_quanta"
$LOCATION"C307"
CDS_LOCATION"C307"
$SEC"1"
CDS_SEC"1";
"B"
$PN"2"28;
"A"
$PN"1"14;
%"Q_CAP"
"1","(-6350,3050)","0","pure_quanta","I15";
;
PART_NUMBER"CH622KMEB01"
VOLTAGE"4V"
TOLERANCE"20%"
VALUE"22UF"
PACK_TYPE"C0402"
MATERIAL"X6S"
$LOCATION"C427"
CDS_LIB"pure_quanta"
CDS_LOCATION"C427"
$SEC"1"
CDS_SEC"1";
"B"
$PN"2"15;
"A"
$PN"1"2;
%"Q_CAP"
"1","(-6350,3850)","0","pure_quanta","I16";
;
PART_NUMBER"CH647KMEA04"
VOLTAGE"4V"
TOLERANCE"20%"
PACK_TYPE"C0805"
VALUE"47UF"
MATERIAL"X6S"
$LOCATION"C235"
CDS_LIB"pure_quanta"
$LOCATION"C235"
CDS_LOCATION"C235"
$SEC"1"
CDS_SEC"1";
"B"
$PN"2"18;
"A"
$PN"1"3;
%"Q_CAP"
"1","(-5900,3050)","0","pure_quanta","I17";
;
PART_NUMBER"CH622KMEB01"
VOLTAGE"4V"
TOLERANCE"20%"
PACK_TYPE"C0402"
VALUE"22UF"
MATERIAL"X6S"
$LOCATION"C429"
CDS_LIB"pure_quanta"
CDS_LOCATION"C429"
$SEC"1"
CDS_SEC"1";
"B"
$PN"2"15;
"A"
$PN"1"2;
%"Q_CAP"
"1","(-5900,3850)","0","pure_quanta","I18";
;
PART_NUMBER"CH647KMEA04"
VOLTAGE"4V"
TOLERANCE"20%"
PACK_TYPE"C0805"
MATERIAL"X6S"
VALUE"47UF"
$LOCATION"C240"
CDS_LIB"pure_quanta"
$LOCATION"C240"
CDS_LOCATION"C240"
$SEC"1"
CDS_SEC"1";
"B"
$PN"2"18;
"A"
$PN"1"3;
%"Q_CAP"
"1","(-6350,4625)","0","pure_quanta","I19";
;
PART_NUMBER"CH6101MEB03"
VOLTAGE"6.3V"
VALUE"10UF"
TOLERANCE"20%"
MATERIAL"X6S"
PACK_TYPE"C0402"
$LOCATION"C234"
CDS_LIB"pure_quanta"
$LOCATION"C234"
CDS_LOCATION"C234"
$SEC"1"
CDS_SEC"1";
"B"
$PN"2"19;
"A"
$PN"1"4;
%"Q_CAP"
"1","(-6800,2225)","0","pure_quanta","I2";
;
PART_NUMBER"CH622KMEB01"
VOLTAGE"4V"
TOLERANCE"20%"
VALUE"22UF"
PACK_TYPE"C0402"
MATERIAL"X6S"
$LOCATION"C426"
CDS_LIB"pure_quanta"
CDS_LOCATION"C426"
$SEC"1"
CDS_SEC"1";
"B"
$PN"2"17;
"A"
$PN"1"1;
%"Q_CAP"
"1","(-5900,4625)","0","pure_quanta","I20";
;
PART_NUMBER"CH6101MEB03"
VALUE"10UF"
VOLTAGE"6.3V"
PACK_TYPE"C0402"
MATERIAL"X6S"
TOLERANCE"20%"
$LOCATION"C239"
CDS_LIB"pure_quanta"
$LOCATION"C239"
CDS_LOCATION"C239"
$SEC"1"
CDS_SEC"1";
"B"
$PN"2"19;
"A"
$PN"1"4;
%"UNIVERSAL_POWER"
"1","(-7250,4900)","0","logical_power","I21";
;
HDL_POWER"PVCCIN_CPU1"
CDS_LIB"logical_power";
"A"4;
%"Q_CAP"
"1","(-7250,5400)","0","pure_quanta","I22";
;
PART_NUMBER"CH6101MEB03"
VOLTAGE"6.3V"
TOLERANCE"20%"
PACK_TYPE"C0402"
MATERIAL"X6S"
VALUE"10UF"
$LOCATION"C223"
CDS_LIB"pure_quanta"
$LOCATION"C223"
CDS_LOCATION"C223"
$SEC"1"
CDS_SEC"1";
"B"
$PN"2"22;
"A"
$PN"1"5;
%"Q_CAP"
"1","(-6800,5400)","0","pure_quanta","I23";
;
PART_NUMBER"CH6101MEB03"
TOLERANCE"20%"
VALUE"10UF"
PACK_TYPE"C0402"
MATERIAL"X6S"
VOLTAGE"6.3V"
$LOCATION"C228"
CDS_LIB"pure_quanta"
$LOCATION"C228"
CDS_LOCATION"C228"
$SEC"1"
CDS_SEC"1";
"B"
$PN"2"22;
"A"
$PN"1"5;
%"UNIVERSAL_POWER"
"1","(-7250,5675)","0","logical_power","I24";
;
HDL_POWER"PVCCIN_CPU1"
CDS_LIB"logical_power";
"A"5;
%"Q_CAP"
"1","(-7275,6150)","0","pure_quanta","I25";
;
PART_NUMBER"CH6101MEB03"
VOLTAGE"6.3V"
VALUE"10UF"
TOLERANCE"20%"
PACK_TYPE"C0402"
MATERIAL"X6S"
$LOCATION"C222"
CDS_LIB"pure_quanta"
$LOCATION"C222"
CDS_LOCATION"C222"
$SEC"1"
CDS_SEC"1";
"B"
$PN"2"21;
"A"
$PN"1"6;
%"Q_CAP"
"1","(-6825,6150)","0","pure_quanta","I26";
;
PART_NUMBER"CH6101MEB03"
VOLTAGE"6.3V"
VALUE"10UF"
TOLERANCE"20%"
PACK_TYPE"C0402"
MATERIAL"X6S"
$LOCATION"C227"
CDS_LIB"pure_quanta"
$LOCATION"C227"
CDS_LOCATION"C227"
$SEC"1"
CDS_SEC"1";
"B"
$PN"2"21;
"A"
$PN"1"6;
%"UNIVERSAL_POWER"
"1","(-7275,6425)","0","logical_power","I27";
;
HDL_POWER"PVCCIN_CPU1"
CDS_LIB"logical_power";
"A"6;
%"Q_CAP"
"1","(-7275,6925)","0","pure_quanta","I28";
;
PART_NUMBER"CH6101MEB03"
VOLTAGE"6.3V"
TOLERANCE"20%"
VALUE"10UF"
PACK_TYPE"C0402"
MATERIAL"X6S"
$LOCATION"C221"
CDS_LIB"pure_quanta"
$LOCATION"C221"
CDS_LOCATION"C221"
$SEC"1"
CDS_SEC"1";
"B"
$PN"2"23;
"A"
$PN"1"7;
%"Q_CAP"
"1","(-6825,6925)","0","pure_quanta","I29";
;
PART_NUMBER"CH6101MEB03"
VOLTAGE"6.3V"
TOLERANCE"20%"
VALUE"10UF"
PACK_TYPE"C0402"
MATERIAL"X6S"
$LOCATION"C226"
CDS_LIB"pure_quanta"
$LOCATION"C226"
CDS_LOCATION"C226"
$SEC"1"
CDS_SEC"1";
"B"
$PN"2"23;
"A"
$PN"1"7;
%"UNIVERSAL_POWER"
"1","(-7250,2500)","0","logical_power","I3";
;
HDL_POWER"PVCCFA_EHV_FIVRA_CPU1"
CDS_LIB"logical_power";
"A"1;
%"Q_CAP"
"1","(-6350,5400)","0","pure_quanta","I30";
;
PART_NUMBER"CH6101MEB03"
VALUE"10UF"
VOLTAGE"6.3V"
TOLERANCE"20%"
MATERIAL"X6S"
PACK_TYPE"C0402"
$LOCATION"C233"
CDS_LIB"pure_quanta"
$LOCATION"C233"
CDS_LOCATION"C233"
$SEC"1"
CDS_SEC"1";
"B"
$PN"2"22;
"A"
$PN"1"5;
%"Q_CAP"
"1","(-5900,5400)","0","pure_quanta","I31";
;
PART_NUMBER"CH6101MEB03"
PACK_TYPE"C0402"
TOLERANCE"20%"
VOLTAGE"6.3V"
MATERIAL"X6S"
VALUE"10UF"
$LOCATION"C238"
CDS_LIB"pure_quanta"
$LOCATION"C238"
CDS_LOCATION"C238"
$SEC"1"
CDS_SEC"1";
"B"
$PN"2"22;
"A"
$PN"1"5;
%"Q_CAP"
"1","(-6375,6150)","0","pure_quanta","I32";
;
PART_NUMBER"CH6101MEB03"
VOLTAGE"6.3V"
VALUE"10UF"
TOLERANCE"20%"
PACK_TYPE"C0402"
MATERIAL"X6S"
$LOCATION"C232"
CDS_LIB"pure_quanta"
$LOCATION"C232"
CDS_LOCATION"C232"
$SEC"1"
CDS_SEC"1";
"B"
$PN"2"21;
"A"
$PN"1"6;
%"Q_CAP"
"1","(-6375,6925)","0","pure_quanta","I33";
;
PART_NUMBER"CH6101MEB03"
VOLTAGE"6.3V"
TOLERANCE"20%"
VALUE"10UF"
PACK_TYPE"C0402"
MATERIAL"X6S"
$LOCATION"C231"
CDS_LIB"pure_quanta"
$LOCATION"C231"
CDS_LOCATION"C231"
$SEC"1"
CDS_SEC"1";
"B"
$PN"2"23;
"A"
$PN"1"7;
%"Q_CAP"
"1","(-5925,6150)","0","pure_quanta","I34";
;
PART_NUMBER"CH6101MEB03"
TOLERANCE"20%"
VALUE"10UF"
VOLTAGE"6.3V"
MATERIAL"X6S"
PACK_TYPE"C0402"
$LOCATION"C237"
CDS_LIB"pure_quanta"
$LOCATION"C237"
CDS_LOCATION"C237"
$SEC"1"
CDS_SEC"1";
"B"
$PN"2"21;
"A"
$PN"1"6;
%"Q_CAP"
"1","(-5925,6925)","0","pure_quanta","I35";
;
PART_NUMBER"CH6101MEB03"
TOLERANCE"20%"
VOLTAGE"6.3V"
PACK_TYPE"C0402"
MATERIAL"X6S"
VALUE"10UF"
$LOCATION"C236"
CDS_LIB"pure_quanta"
$LOCATION"C236"
CDS_LOCATION"C236"
$SEC"1"
CDS_SEC"1";
"B"
$PN"2"23;
"A"
$PN"1"7;
%"UNIVERSAL_POWER"
"1","(-7275,7200)","0","logical_power","I36";
;
HDL_POWER"PVCCIN_CPU1"
CDS_LIB"logical_power";
"A"7;
%"Q_CAP"
"1","(-5450,2225)","0","pure_quanta","I37";
;
PART_NUMBER"CH622KMEB01"
VOLTAGE"4V"
TOLERANCE"20%"
PACK_TYPE"C0402"
VALUE"22UF"
MATERIAL"X6S"
$LOCATION"C431"
CDS_LIB"pure_quanta"
CDS_LOCATION"C431"
$SEC"1"
CDS_SEC"1";
"B"
$PN"2"17;
"A"
$PN"1"1;
%"Q_CAP"
"1","(-5000,2225)","0","pure_quanta","I38";
;
PART_NUMBER"CH622KMEB01"
TOLERANCE"20%"
VOLTAGE"4V"
VALUE"22UF"
PACK_TYPE"C0402"
MATERIAL"X6S"
$LOCATION"C433"
CDS_LIB"pure_quanta"
CDS_LOCATION"C433"
$SEC"1"
CDS_SEC"1";
"B"
$PN"2"17;
"A"
$PN"1"1;
%"Q_CAP"
"1","(-4550,2225)","0","pure_quanta","I39";
;
PART_NUMBER"CH622KMEB01"
VOLTAGE"4V"
TOLERANCE"20%"
VALUE"22UF"
MATERIAL"X6S"
PACK_TYPE"C0402"
$LOCATION"C435"
CDS_LIB"pure_quanta"
CDS_LOCATION"C435"
$SEC"1"
CDS_SEC"1";
"B"
$PN"2"17;
"A"
$PN"1"1;
%"Q_CAP"
"1","(-6350,2225)","0","pure_quanta","I4";
;
PART_NUMBER"CH622KMEB01"
TOLERANCE"20%"
VOLTAGE"4V"
MATERIAL"X6S"
VALUE"22UF"
PACK_TYPE"C0402"
$LOCATION"C428"
CDS_LIB"pure_quanta"
CDS_LOCATION"C428"
$SEC"1"
CDS_SEC"1";
"B"
$PN"2"17;
"A"
$PN"1"1;
%"Q_CAP"
"1","(-4100,2225)","0","pure_quanta","I40";
;
PART_NUMBER"CH622KMEB01"
VOLTAGE"4V"
TOLERANCE"20%"
VALUE"22UF"
PACK_TYPE"C0402"
MATERIAL"X6S"
$LOCATION"C437"
CDS_LIB"pure_quanta"
CDS_LOCATION"C437"
$SEC"1"
CDS_SEC"1";
"B"
$PN"2"17;
"A"
$PN"1"1;
%"Q_CAP"
"1","(-5450,3850)","0","pure_quanta","I41";
;
PART_NUMBER"CH647KMEA04"
TOLERANCE"20%"
VOLTAGE"4V"
PACK_TYPE"C0805"
MATERIAL"X6S"
VALUE"47UF"
$LOCATION"C245"
CDS_LIB"pure_quanta"
$LOCATION"C245"
CDS_LOCATION"C245"
$SEC"1"
CDS_SEC"1";
"B"
$PN"2"18;
"A"
$PN"1"3;
%"Q_CAP"
"1","(-5000,3050)","0","pure_quanta","I42";
;
PART_NUMBER"CH622KMEB01"
TOLERANCE"20%"
VALUE"22UF"
VOLTAGE"4V"
MATERIAL"X6S"
PACK_TYPE"C0402"
$LOCATION"C432"
CDS_LIB"pure_quanta"
CDS_LOCATION"C432"
$SEC"1"
CDS_SEC"1";
"B"
$PN"2"16;
"A"
$PN"1"8;
%"UNIVERSAL_POWER"
"1","(-5000,3325)","0","logical_power","I43";
;
HDL_POWER"PVCCINFAON_CPU1"
CDS_LIB"logical_power";
"A"8;
%"Q_CAP"
"1","(-5000,3850)","0","pure_quanta","I44";
;
PART_NUMBER"CH647KMEA04"
TOLERANCE"20%"
VOLTAGE"4V"
PACK_TYPE"C0805"
MATERIAL"X6S"
VALUE"47UF"
$LOCATION"C250"
CDS_LIB"pure_quanta"
$LOCATION"C250"
CDS_LOCATION"C250"
$SEC"1"
CDS_SEC"1";
"B"
$PN"2"18;
"A"
$PN"1"3;
%"Q_CAP"
"1","(-5450,4625)","0","pure_quanta","I45";
;
PART_NUMBER"CH6101MEB03"
VALUE"10UF"
VOLTAGE"6.3V"
PACK_TYPE"C0402"
TOLERANCE"20%"
MATERIAL"X6S"
$LOCATION"C244"
CDS_LIB"pure_quanta"
$LOCATION"C244"
CDS_LOCATION"C244"
$SEC"1"
CDS_SEC"1";
"B"
$PN"2"19;
"A"
$PN"1"4;
%"Q_CAP"
"1","(-5000,4625)","0","pure_quanta","I46";
;
PART_NUMBER"CH6101MEB03"
VALUE"10UF"
VOLTAGE"6.3V"
PACK_TYPE"C0402"
MATERIAL"X6S"
TOLERANCE"20%"
$LOCATION"C249"
CDS_LIB"pure_quanta"
$LOCATION"C249"
CDS_LOCATION"C249"
$SEC"1"
CDS_SEC"1";
"B"
$PN"2"19;
"A"
$PN"1"4;
%"Q_CAP"
"1","(-4550,3050)","0","pure_quanta","I47";
;
PART_NUMBER"CH622KMEB01"
TOLERANCE"20%"
VALUE"22UF"
VOLTAGE"4V"
MATERIAL"X6S"
PACK_TYPE"C0402"
$LOCATION"C434"
CDS_LIB"pure_quanta"
CDS_LOCATION"C434"
$SEC"1"
CDS_SEC"1";
"B"
$PN"2"16;
"A"
$PN"1"8;
%"Q_CAP"
"1","(-4550,3850)","0","pure_quanta","I48";
;
PART_NUMBER"CH647KMEA04"
TOLERANCE"20%"
VOLTAGE"4V"
PACK_TYPE"C0805"
VALUE"47UF"
MATERIAL"X6S"
$LOCATION"C255"
CDS_LIB"pure_quanta"
$LOCATION"C255"
CDS_LOCATION"C255"
$SEC"1"
CDS_SEC"1";
"B"
$PN"2"18;
"A"
$PN"1"3;
%"Q_CAP"
"1","(-4100,3050)","0","pure_quanta","I49";
;
PART_NUMBER"CH622KMEB01"
VOLTAGE"4V"
VALUE"22UF"
TOLERANCE"20%"
PACK_TYPE"C0402"
MATERIAL"X6S"
$LOCATION"C436"
CDS_LIB"pure_quanta"
CDS_LOCATION"C436"
$SEC"1"
CDS_SEC"1";
"B"
$PN"2"16;
"A"
$PN"1"8;
%"Q_CAP"
"1","(-5900,2225)","0","pure_quanta","I5";
;
PART_NUMBER"CH622KMEB01"
TOLERANCE"20%"
VOLTAGE"4V"
MATERIAL"X6S"
PACK_TYPE"C0402"
VALUE"22UF"
$LOCATION"C430"
CDS_LIB"pure_quanta"
CDS_LOCATION"C430"
$SEC"1"
CDS_SEC"1";
"B"
$PN"2"17;
"A"
$PN"1"1;
%"Q_CAP"
"1","(-4100,3850)","0","pure_quanta","I50";
;
PART_NUMBER"CH647KMEA04"
VOLTAGE"4V"
TOLERANCE"20%"
PACK_TYPE"C0805"
VALUE"47UF"
MATERIAL"X6S"
$LOCATION"C260"
CDS_LIB"pure_quanta"
$LOCATION"C260"
CDS_LOCATION"C260"
$SEC"1"
CDS_SEC"1";
"B"
$PN"2"18;
"A"
$PN"1"3;
%"Q_CAP"
"1","(-4550,4625)","0","pure_quanta","I51";
;
PART_NUMBER"CH6101MEB03"
VALUE"10UF"
VOLTAGE"6.3V"
MATERIAL"X6S"
TOLERANCE"20%"
PACK_TYPE"C0402"
$LOCATION"C254"
CDS_LIB"pure_quanta"
$LOCATION"C254"
CDS_LOCATION"C254"
$SEC"1"
CDS_SEC"1";
"B"
$PN"2"19;
"A"
$PN"1"4;
%"Q_CAP"
"1","(-4100,4625)","0","pure_quanta","I52";
;
PART_NUMBER"CH6101MEB03"
VOLTAGE"6.3V"
VALUE"10UF"
TOLERANCE"20%"
MATERIAL"X6S"
PACK_TYPE"C0402"
$LOCATION"C259"
CDS_LIB"pure_quanta"
$LOCATION"C259"
CDS_LOCATION"C259"
$SEC"1"
CDS_SEC"1";
"B"
$PN"2"19;
"A"
$PN"1"4;
%"Q_CAP"
"1","(-3650,2225)","0","pure_quanta","I53";
;
PART_NUMBER"CH622KMEB01"
PACK_TYPE"C0402"
VOLTAGE"4V"
TOLERANCE"20%"
VALUE"22UF"
MATERIAL"X6S"
$LOCATION"C439"
CDS_LIB"pure_quanta"
CDS_LOCATION"C439"
$SEC"1"
CDS_SEC"1";
"B"
$PN"2"17;
"A"
$PN"1"1;
%"UNIVERSAL_GND"
"1","(-3200,2700)","0","logical_power","I54";
;
CDS_LIB"logical_power"
HDL_POWER"GND";
"A"16;
%"Q_CAP"
"1","(-3200,2225)","0","pure_quanta","I55";
;
PART_NUMBER"CH622KMEB01"
TOLERANCE"20%"
VOLTAGE"4V"
PACK_TYPE"C0402"
VALUE"22UF"
MATERIAL"X6S"
$LOCATION"C441"
CDS_LIB"pure_quanta"
CDS_LOCATION"C441"
$SEC"1"
CDS_SEC"1";
"B"
$PN"2"17;
"A"
$PN"1"1;
%"UNIVERSAL_GND"
"1","(-2750,1875)","0","logical_power","I56";
;
CDS_LIB"logical_power"
HDL_POWER"GND";
"A"17;
%"Q_CAP"
"1","(-2750,2225)","0","pure_quanta","I57";
;
PART_NUMBER"CH622KMEB01"
VOLTAGE"4V"
TOLERANCE"20%"
MATERIAL"X6S"
PACK_TYPE"C0402"
VALUE"22UF"
$LOCATION"C442"
CDS_LIB"pure_quanta"
CDS_LOCATION"C442"
$SEC"1"
CDS_SEC"1";
"B"
$PN"2"17;
"A"
$PN"1"1;
%"Q_CAP"
"1","(-3650,3050)","0","pure_quanta","I58";
;
PART_NUMBER"CH622KMEB01"
TOLERANCE"20%"
VOLTAGE"4V"
VALUE"22UF"
MATERIAL"X6S"
PACK_TYPE"C0402"
$LOCATION"C438"
CDS_LIB"pure_quanta"
CDS_LOCATION"C438"
$SEC"1"
CDS_SEC"1";
"B"
$PN"2"16;
"A"
$PN"1"8;
%"Q_CAP"
"1","(-3650,3850)","0","pure_quanta","I59";
;
PART_NUMBER"CH647KMEA04"
VOLTAGE"4V"
TOLERANCE"20%"
PACK_TYPE"C0805"
VALUE"47UF"
MATERIAL"X6S"
$LOCATION"C265"
CDS_LIB"pure_quanta"
$LOCATION"C265"
CDS_LOCATION"C265"
$SEC"1"
CDS_SEC"1";
"B"
$PN"2"18;
"A"
$PN"1"3;
%"UNIVERSAL_GND"
"1","(-5900,2725)","0","logical_power","I6";
;
CDS_LIB"logical_power"
HDL_POWER"GND";
"A"15;
%"UNIVERSAL_GND"
"1","(-3200,3500)","0","logical_power","I60";
;
CDS_LIB"logical_power"
HDL_POWER"GND";
"A"18;
%"Q_CAP"
"1","(-3200,3050)","0","pure_quanta","I61";
;
PART_NUMBER"CH622KMEB01"
MATERIAL"X6S"
TOLERANCE"20%"
VALUE"22UF"
VOLTAGE"4V"
PACK_TYPE"C0402"
$LOCATION"C440"
CDS_LIB"pure_quanta"
CDS_LOCATION"C440"
$SEC"1"
CDS_SEC"1";
"B"
$PN"2"16;
"A"
$PN"1"8;
%"Q_CAP"
"1","(-3200,3850)","0","pure_quanta","I62";
;
PART_NUMBER"CH647KMEA04"
VOLTAGE"4V"
TOLERANCE"20%"
PACK_TYPE"C0805"
MATERIAL"X6S"
VALUE"47UF"
$LOCATION"C270"
CDS_LIB"pure_quanta"
$LOCATION"C270"
CDS_LOCATION"C270"
$SEC"1"
CDS_SEC"1";
"B"
$PN"2"18;
"A"
$PN"1"3;
%"Q_CAP"
"1","(-3650,4625)","0","pure_quanta","I63";
;
PART_NUMBER"CH6101MEB03"
VOLTAGE"6.3V"
VALUE"10UF"
MATERIAL"X6S"
TOLERANCE"20%"
PACK_TYPE"C0402"
$LOCATION"C264"
CDS_LIB"pure_quanta"
$LOCATION"C264"
CDS_LOCATION"C264"
$SEC"1"
CDS_SEC"1";
"B"
$PN"2"19;
"A"
$PN"1"4;
%"Q_CAP"
"1","(-3200,4625)","0","pure_quanta","I64";
;
PART_NUMBER"CH6101MEB03"
VOLTAGE"6.3V"
VALUE"10UF"
MATERIAL"X6S"
TOLERANCE"20%"
PACK_TYPE"C0402"
$LOCATION"C269"
CDS_LIB"pure_quanta"
$LOCATION"C269"
CDS_LOCATION"C269"
$SEC"1"
CDS_SEC"1";
"B"
$PN"2"19;
"A"
$PN"1"4;
%"UNIVERSAL_GND"
"1","(-3200,4275)","0","logical_power","I65";
;
CDS_LIB"logical_power"
HDL_POWER"GND";
"A"19;
%"Q_CAP"
"1","(-2725,4625)","0","pure_quanta","I66";
;
PART_NUMBER"CH622KMEB01"
VOLTAGE"4V"
TOLERANCE"20%"
PACK_TYPE"C0402"
MATERIAL"X6S"
VALUE"22UF"
$LOCATION"C274"
CDS_LIB"pure_quanta"
$LOCATION"C274"
CDS_LOCATION"C274"
$SEC"1"
CDS_SEC"1";
"B"
$PN"2"25;
"A"
$PN"1"11;
%"Q_CAP"
"1","(-1975,3050)","0","pure_quanta","I67";
;
PART_NUMBER"CH622KMEB01"
VALUE"22UF"
VOLTAGE"4V"
TOLERANCE"20%"
PACK_TYPE"C0402"
MATERIAL"X6S"
$LOCATION"C443"
CDS_LIB"pure_quanta"
CDS_LOCATION"C443"
$SEC"1"
CDS_SEC"1";
"B"
$PN"2"24;
"A"
$PN"1"9;
%"UNIVERSAL_POWER"
"1","(-1975,3325)","0","logical_power","I68";
;
HDL_POWER"PVCCFA_EHV_CPU1"
CDS_LIB"logical_power";
"A"9;
%"UNIVERSAL_GND"
"1","(-1975,3500)","0","logical_power","I69";
;
CDS_LIB"logical_power"
HDL_POWER"GND";
"A"20;
%"Q_CAP"
"1","(-7250,3050)","0","pure_quanta","I7";
;
PART_NUMBER"CH622KMEB01"
TOLERANCE"20%"
VOLTAGE"4V"
PACK_TYPE"C0402"
MATERIAL"X6S"
VALUE"22UF"
$LOCATION"C423"
CDS_LIB"pure_quanta"
CDS_LOCATION"C423"
$SEC"1"
CDS_SEC"1";
"B"
$PN"2"15;
"A"
$PN"1"2;
%"Q_CAP"
"1","(-1975,3775)","0","pure_quanta","I70";
;
PART_NUMBER"CH622KMEB01"
VOLTAGE"4V"
VALUE"22UF"
MATERIAL"X6S"
TOLERANCE"20%"
PACK_TYPE"C0402"
$LOCATION"C310"
CDS_LIB"pure_quanta"
$LOCATION"C310"
CDS_LOCATION"C310"
$SEC"1"
CDS_SEC"1";
"B"
$PN"2"20;
"A"
$PN"1"10;
%"Q_CAP"
"1","(-2275,4625)","0","pure_quanta","I71";
;
PART_NUMBER"CH622KMEB01"
TOLERANCE"20%"
VOLTAGE"4V"
MATERIAL"X6S"
VALUE"22UF"
PACK_TYPE"C0402"
$LOCATION"C278"
CDS_LIB"pure_quanta"
$LOCATION"C278"
CDS_LOCATION"C278"
$SEC"1"
CDS_SEC"1";
"B"
$PN"2"25;
"A"
$PN"1"11;
%"UNIVERSAL_POWER"
"1","(-1975,4050)","0","logical_power","I72";
;
HDL_POWER"PVNN_MAIN_CPU1"
CDS_LIB"logical_power";
"A"10;
%"Q_CAP"
"1","(-1825,4625)","0","pure_quanta","I73";
;
PART_NUMBER"CH622KMEB01"
TOLERANCE"20%"
VOLTAGE"4V"
MATERIAL"X6S"
VALUE"22UF"
PACK_TYPE"C0402"
$LOCATION"C282"
CDS_LIB"pure_quanta"
$LOCATION"C282"
CDS_LOCATION"C282"
$SEC"1"
CDS_SEC"1";
"B"
$PN"2"25;
"A"
$PN"1"11;
%"Q_CAP"
"1","(-5450,5400)","0","pure_quanta","I74";
;
PART_NUMBER"CH6101MEB03"
TOLERANCE"20%"
VOLTAGE"6.3V"
MATERIAL"X6S"
PACK_TYPE"C0402"
VALUE"10UF"
$LOCATION"C243"
CDS_LIB"pure_quanta"
$LOCATION"C243"
CDS_LOCATION"C243"
$SEC"1"
CDS_SEC"1";
"B"
$PN"2"22;
"A"
$PN"1"5;
%"Q_CAP"
"1","(-5000,5400)","0","pure_quanta","I75";
;
PART_NUMBER"CH6101MEB03"
TOLERANCE"20%"
VOLTAGE"6.3V"
MATERIAL"X6S"
PACK_TYPE"C0402"
VALUE"10UF"
$LOCATION"C248"
CDS_LIB"pure_quanta"
$LOCATION"C248"
CDS_LOCATION"C248"
$SEC"1"
CDS_SEC"1";
"B"
$PN"2"22;
"A"
$PN"1"5;
%"Q_CAP"
"1","(-5475,6150)","0","pure_quanta","I76";
;
PART_NUMBER"CH6101MEB03"
TOLERANCE"20%"
VALUE"10UF"
VOLTAGE"6.3V"
MATERIAL"X6S"
PACK_TYPE"C0402"
$LOCATION"C242"
CDS_LIB"pure_quanta"
$LOCATION"C242"
CDS_LOCATION"C242"
$SEC"1"
CDS_SEC"1";
"B"
$PN"2"21;
"A"
$PN"1"6;
%"Q_CAP"
"1","(-5475,6925)","0","pure_quanta","I77";
;
PART_NUMBER"CH6101MEB03"
TOLERANCE"20%"
VOLTAGE"6.3V"
MATERIAL"X6S"
PACK_TYPE"C0402"
VALUE"10UF"
$LOCATION"C241"
CDS_LIB"pure_quanta"
$LOCATION"C241"
CDS_LOCATION"C241"
$SEC"1"
CDS_SEC"1";
"B"
$PN"2"23;
"A"
$PN"1"7;
%"Q_CAP"
"1","(-5025,6150)","0","pure_quanta","I78";
;
PART_NUMBER"CH6101MEB03"
TOLERANCE"20%"
VALUE"10UF"
VOLTAGE"6.3V"
PACK_TYPE"C0402"
MATERIAL"X6S"
$LOCATION"C247"
CDS_LIB"pure_quanta"
$LOCATION"C247"
CDS_LOCATION"C247"
$SEC"1"
CDS_SEC"1";
"B"
$PN"2"21;
"A"
$PN"1"6;
%"Q_CAP"
"1","(-5025,6925)","0","pure_quanta","I79";
;
PART_NUMBER"CH6101MEB03"
TOLERANCE"20%"
VOLTAGE"6.3V"
MATERIAL"X6S"
PACK_TYPE"C0402"
VALUE"10UF"
$LOCATION"C246"
CDS_LIB"pure_quanta"
$LOCATION"C246"
CDS_LOCATION"C246"
$SEC"1"
CDS_SEC"1";
"B"
$PN"2"23;
"A"
$PN"1"7;
%"Q_CAP"
"1","(-6800,3050)","0","pure_quanta","I8";
;
PART_NUMBER"CH622KMEB01"
VOLTAGE"4V"
PACK_TYPE"C0402"
MATERIAL"X6S"
VALUE"22UF"
TOLERANCE"20%"
$LOCATION"C425"
CDS_LIB"pure_quanta"
CDS_LOCATION"C425"
$SEC"1"
CDS_SEC"1";
"B"
$PN"2"15;
"A"
$PN"1"2;
%"Q_CAP"
"1","(-4550,5400)","0","pure_quanta","I80";
;
PART_NUMBER"CH6101MEB03"
TOLERANCE"20%"
VOLTAGE"6.3V"
MATERIAL"X6S"
PACK_TYPE"C0402"
VALUE"10UF"
$LOCATION"C253"
CDS_LIB"pure_quanta"
$LOCATION"C253"
CDS_LOCATION"C253"
$SEC"1"
CDS_SEC"1";
"B"
$PN"2"22;
"A"
$PN"1"5;
%"Q_CAP"
"1","(-4100,5400)","0","pure_quanta","I81";
;
PART_NUMBER"CH6101MEB03"
VOLTAGE"6.3V"
TOLERANCE"20%"
VALUE"10UF"
PACK_TYPE"C0402"
MATERIAL"X6S"
$LOCATION"C258"
CDS_LIB"pure_quanta"
$LOCATION"C258"
CDS_LOCATION"C258"
$SEC"1"
CDS_SEC"1";
"B"
$PN"2"22;
"A"
$PN"1"5;
%"Q_CAP"
"1","(-4575,6150)","0","pure_quanta","I82";
;
PART_NUMBER"CH6101MEB03"
TOLERANCE"20%"
VALUE"10UF"
VOLTAGE"6.3V"
PACK_TYPE"C0402"
MATERIAL"X6S"
$LOCATION"C252"
CDS_LIB"pure_quanta"
$LOCATION"C252"
CDS_LOCATION"C252"
$SEC"1"
CDS_SEC"1";
"B"
$PN"2"21;
"A"
$PN"1"6;
%"Q_CAP"
"1","(-4575,6925)","0","pure_quanta","I83";
;
PART_NUMBER"CH6101MEB03"
TOLERANCE"20%"
VOLTAGE"6.3V"
MATERIAL"X6S"
PACK_TYPE"C0402"
VALUE"10UF"
$LOCATION"C251"
CDS_LIB"pure_quanta"
$LOCATION"C251"
CDS_LOCATION"C251"
$SEC"1"
CDS_SEC"1";
"B"
$PN"2"23;
"A"
$PN"1"7;
%"Q_CAP"
"1","(-4125,6150)","0","pure_quanta","I84";
;
PART_NUMBER"CH6101MEB03"
VOLTAGE"6.3V"
VALUE"10UF"
TOLERANCE"20%"
MATERIAL"X6S"
PACK_TYPE"C0402"
$LOCATION"C257"
CDS_LIB"pure_quanta"
$LOCATION"C257"
CDS_LOCATION"C257"
$SEC"1"
CDS_SEC"1";
"B"
$PN"2"21;
"A"
$PN"1"6;
%"Q_CAP"
"1","(-4125,6925)","0","pure_quanta","I85";
;
PART_NUMBER"CH6101MEB03"
VOLTAGE"6.3V"
TOLERANCE"20%"
VALUE"10UF"
PACK_TYPE"C0402"
MATERIAL"X6S"
$LOCATION"C256"
CDS_LIB"pure_quanta"
$LOCATION"C256"
CDS_LOCATION"C256"
$SEC"1"
CDS_SEC"1";
"B"
$PN"2"23;
"A"
$PN"1"7;
%"Q_CAP"
"1","(-3650,5400)","0","pure_quanta","I86";
;
PART_NUMBER"CH6101MEB03"
VOLTAGE"6.3V"
TOLERANCE"20%"
VALUE"10UF"
PACK_TYPE"C0402"
MATERIAL"X6S"
$LOCATION"C263"
CDS_LIB"pure_quanta"
$LOCATION"C263"
CDS_LOCATION"C263"
$SEC"1"
CDS_SEC"1";
"B"
$PN"2"22;
"A"
$PN"1"5;
%"UNIVERSAL_GND"
"1","(-3225,5800)","0","logical_power","I87";
;
CDS_LIB"logical_power"
HDL_POWER"GND";
"A"21;
%"Q_CAP"
"1","(-3200,5400)","0","pure_quanta","I88";
;
PART_NUMBER"CH6101MEB03"
VOLTAGE"6.3V"
TOLERANCE"20%"
VALUE"10UF"
PACK_TYPE"C0402"
MATERIAL"X6S"
$LOCATION"C268"
CDS_LIB"pure_quanta"
$LOCATION"C268"
CDS_LOCATION"C268"
$SEC"1"
CDS_SEC"1";
"B"
$PN"2"22;
"A"
$PN"1"5;
%"UNIVERSAL_GND"
"1","(-3200,5050)","0","logical_power","I89";
;
CDS_LIB"logical_power"
HDL_POWER"GND";
"A"22;
%"UNIVERSAL_POWER"
"1","(-7250,3325)","0","logical_power","I9";
;
HDL_POWER"PVCCD_HV_CPU1"
CDS_LIB"logical_power";
"A"2;
%"UNIVERSAL_POWER"
"1","(-2725,4900)","0","logical_power","I90";
;
HDL_POWER"PVCCIN_CPU1"
CDS_LIB"logical_power";
"A"11;
%"Q_CAP"
"1","(-2725,5400)","0","pure_quanta","I91";
;
PART_NUMBER"CH622KMEB01"
VOLTAGE"4V"
PACK_TYPE"C0402"
MATERIAL"X6S"
VALUE"22UF"
TOLERANCE"20%"
$LOCATION"C273"
CDS_LIB"pure_quanta"
$LOCATION"C273"
CDS_LOCATION"C273"
$SEC"1"
CDS_SEC"1";
"B"
$PN"2"26;
"A"
$PN"1"12;
%"UNIVERSAL_POWER"
"1","(-2725,5675)","0","logical_power","I92";
;
HDL_POWER"PVCCIN_CPU1"
CDS_LIB"logical_power";
"A"12;
%"Q_CAP"
"1","(-3675,6150)","0","pure_quanta","I93";
;
PART_NUMBER"CH6101MEB03"
VOLTAGE"6.3V"
VALUE"10UF"
TOLERANCE"20%"
PACK_TYPE"C0402"
MATERIAL"X6S"
$LOCATION"C262"
CDS_LIB"pure_quanta"
$LOCATION"C262"
CDS_LOCATION"C262"
$SEC"1"
CDS_SEC"1";
"B"
$PN"2"21;
"A"
$PN"1"6;
%"Q_CAP"
"1","(-3225,6150)","0","pure_quanta","I94";
;
PART_NUMBER"CH6101MEB03"
VOLTAGE"6.3V"
VALUE"10UF"
TOLERANCE"20%"
PACK_TYPE"C0402"
MATERIAL"X6S"
$LOCATION"C267"
CDS_LIB"pure_quanta"
$LOCATION"C267"
CDS_LOCATION"C267"
$SEC"1"
CDS_SEC"1";
"B"
$PN"2"21;
"A"
$PN"1"6;
%"Q_CAP"
"1","(-3675,6925)","0","pure_quanta","I95";
;
PART_NUMBER"CH6101MEB03"
VOLTAGE"6.3V"
TOLERANCE"20%"
VALUE"10UF"
PACK_TYPE"C0402"
MATERIAL"X6S"
$LOCATION"C261"
CDS_LIB"pure_quanta"
$LOCATION"C261"
CDS_LOCATION"C261"
$SEC"1"
CDS_SEC"1";
"B"
$PN"2"23;
"A"
$PN"1"7;
%"UNIVERSAL_GND"
"1","(-3225,6575)","0","logical_power","I96";
;
CDS_LIB"logical_power"
HDL_POWER"GND";
"A"23;
%"Q_CAP"
"1","(-3225,6925)","0","pure_quanta","I97";
;
PART_NUMBER"CH6101MEB03"
VOLTAGE"6.3V"
TOLERANCE"20%"
VALUE"10UF"
PACK_TYPE"C0402"
MATERIAL"X6S"
$LOCATION"C266"
CDS_LIB"pure_quanta"
$LOCATION"C266"
CDS_LOCATION"C266"
$SEC"1"
CDS_SEC"1";
"B"
$PN"2"23;
"A"
$PN"1"7;
%"Q_CAP"
"1","(-2750,6150)","0","pure_quanta","I98";
;
PART_NUMBER"CH622KMEB01"
TOLERANCE"20%"
VOLTAGE"4V"
VALUE"22UF"
PACK_TYPE"C0402"
MATERIAL"X6S"
$LOCATION"C272"
CDS_LIB"pure_quanta"
$LOCATION"C272"
CDS_LOCATION"C272"
$SEC"1"
CDS_SEC"1";
"B"
$PN"2"27;
"A"
$PN"1"13;
%"UNIVERSAL_POWER"
"1","(-2750,6425)","0","logical_power","I99";
;
HDL_POWER"PVCCIN_CPU1"
CDS_LIB"logical_power";
"A"13;
END.
